(kicad_pcb
	(version 20241229)
	(generator "pcbnew")
	(generator_version "9.0")
	(general
		(thickness 1.61)
		(legacy_teardrops no)
	)
	(paper "A3")
	(title_block
		(title "SO-DIMM DDR5 Tester")
		(date "2025-11-26")
		(rev "1.3.0")
		(comment 9 "footprints 218-222 of 627")
	)
	(layers
		(0 "F.Cu" signal)
		(4 "In1.Cu" power)
		(6 "In2.Cu" mixed)
		(8 "In3.Cu" power)
		(10 "In4.Cu" mixed)
		(12 "In5.Cu" power)
		(14 "In6.Cu" mixed)
		(16 "In7.Cu" power)
		(18 "In8.Cu" power)
		(20 "In9.Cu" mixed)
		(22 "In10.Cu" power)
		(2 "B.Cu" signal)
		(9 "F.Adhes" user "F.Adhesive")
		(11 "B.Adhes" user "B.Adhesive")
		(13 "F.Paste" user)
		(15 "B.Paste" user)
		(5 "F.SilkS" user "F.Silkscreen")
		(7 "B.SilkS" user "B.Silkscreen")
		(1 "F.Mask" user)
		(3 "B.Mask" user)
		(17 "Dwgs.User" user "User.Drawings")
		(19 "Cmts.User" user "User.Comments")
		(21 "Eco1.User" user "User.Eco1")
		(23 "Eco2.User" user "User.Eco2")
		(25 "Edge.Cuts" user)
		(27 "Margin" user)
		(31 "F.CrtYd" user "F.Courtyard")
		(29 "B.CrtYd" user "B.Courtyard")
		(35 "F.Fab" user)
		(33 "B.Fab" user)
	)
	(footprint "antmicro-footprints:R_0402_1005Metric"
		(layer "F.Cu")
		(at 176.080501 197.776 90)
		(descr "Resistor SMD 0402")
		(tags "resistor SMD 0402")
		(property "Reference" "R185"
			(at -3.624 0.299499 90)
			(layer "F.SilkS")
			(effects
				(font
					(size 0.7 0.7)
					(thickness 0.15)
				)
				(justify left bottom)
			)
		)
		(property "Value" "R_80k6_0402"
			(at -1.011843 1.772047 90)
			(layer "F.Fab")
			(effects
				(font
					(size 0.7 0.7)
					(thickness 0.15)
				)
				(justify left bottom)
			)
		)
		(property "Datasheet" "https://www.bourns.com/docs/product-datasheets/cr.pdf"
			(at 0 0 90)
			(layer "F.Fab")
			(hide yes)
			(effects
				(font
					(size 1.27 1.27)
					(thickness 0.15)
				)
			)
		)
		(property "Author" "Antmicro"
			(at 373.856501 21.695499 0)
			(layer "F.Fab")
			(hide yes)
			(effects
				(font
					(size 1 1)
					(thickness 0.15)
				)
			)
		)
		(property "License" "Apache-2.0"
			(at 373.856501 21.695499 0)
			(layer "F.Fab")
			(hide yes)
			(effects
				(font
					(size 1 1)
					(thickness 0.15)
				)
			)
		)
		(property "MPN" "CR0402-FX-8062GLF"
			(at 373.856501 21.695499 0)
			(layer "F.Fab")
			(hide yes)
			(effects
				(font
					(size 1 1)
					(thickness 0.15)
				)
			)
		)
		(property "Manufacturer" "Bourns"
			(at 373.856501 21.695499 0)
			(layer "F.Fab")
			(hide yes)
			(effects
				(font
					(size 1 1)
					(thickness 0.15)
				)
			)
		)
		(property "Tolerance" "1%"
			(at 373.856501 21.695499 0)
			(layer "F.Fab")
			(hide yes)
			(effects
				(font
					(size 1 1)
					(thickness 0.15)
				)
			)
		)
		(property "Val" "80k6"
			(at 373.856501 21.695499 0)
			(layer "F.Fab")
			(hide yes)
			(effects
				(font
					(size 1 1)
					(thickness 0.15)
				)
			)
		)
		(sheetname "/Supply/")
		(sheetfile "supply.kicad_sch")
		(attr smd)
		(fp_rect
			(start -0.93 -0.47)
			(end 0.93 0.47)
			(stroke
				(width 0.05)
				(type solid)
			)
			(fill no)
			(layer "F.CrtYd")
		)
		(fp_rect
			(start -0.5 -0.25)
			(end 0.5 0.25)
			(stroke
				(width 0.15)
				(type solid)
			)
			(fill no)
			(layer "F.Fab")
		)
		(pad "1" smd roundrect
			(at -0.485 0 90)
			(size 0.59 0.64)
			(layers "F.Cu" "F.Mask" "F.Paste")
			(roundrect_rratio 0.25)
			(net 303 "Net-(C221-Pad1)")
			(pintype "passive")
		)
		(pad "2" smd roundrect
			(at 0.485 0 90)
			(size 0.59 0.64)
			(layers "F.Cu" "F.Mask" "F.Paste")
			(roundrect_rratio 0.25)
			(net 78 "/Supply/1V0_REG")
			(pintype "passive")
		)
	)
	(footprint "antmicro-footprints:SW_KMR211NGLFS_SMD"
		(layer "F.Cu")
		(at 182.25 124.146)
		(property "Reference" "SW3"
			(at 2.75 1.054 0)
			(layer "F.SilkS")
			(effects
				(font
					(size 0.7 0.7)
					(thickness 0.15)
				)
				(justify left bottom)
			)
		)
		(property "Value" "SW_KMR211NGLFS_SMD"
			(at 0 2.8 0)
			(layer "F.Fab")
			(effects
				(font
					(size 0.7 0.7)
					(thickness 0.15)
				)
				(justify left bottom)
			)
		)
		(property "Datasheet" "http://www.farnell.com/datasheets/2631211.pdf"
			(at 0 0 0)
			(layer "F.Fab")
			(hide yes)
			(effects
				(font
					(size 1.27 1.27)
					(thickness 0.15)
				)
			)
		)
		(property "Author" "Antmicro"
			(at 0 0 0)
			(layer "F.Fab")
			(hide yes)
			(effects
				(font
					(size 1 1)
					(thickness 0.15)
				)
			)
		)
		(property "License" "Apache-2.0"
			(at 0 0 0)
			(layer "F.Fab")
			(hide yes)
			(effects
				(font
					(size 1 1)
					(thickness 0.15)
				)
			)
		)
		(property "MPN" "KMR211NGLFS"
			(at 0 0 0)
			(layer "F.Fab")
			(hide yes)
			(effects
				(font
					(size 1 1)
					(thickness 0.15)
				)
			)
		)
		(property "Manufacturer" "C&K"
			(at 0 0 0)
			(layer "F.Fab")
			(hide yes)
			(effects
				(font
					(size 1 1)
					(thickness 0.15)
				)
			)
		)
		(sheetname "/DDR5 SODIMM/")
		(sheetfile "ddr5-sodimm.kicad_sch")
		(attr smd)
		(fp_line
			(start -2.1 -1.6)
			(end -2.1 -1.499)
			(stroke
				(width 0.15)
				(type solid)
			)
			(layer "F.SilkS")
		)
		(fp_line
			(start -2.1 1.601)
			(end -2.1 1.48)
			(stroke
				(width 0.15)
				(type solid)
			)
			(layer "F.SilkS")
		)
		(fp_line
			(start 2.101 -1.6)
			(end -2.1 -1.6)
			(stroke
				(width 0.15)
				(type solid)
			)
			(layer "F.SilkS")
		)
		(fp_line
			(start 2.101 -1.58)
			(end 2.101 -1.459)
			(stroke
				(width 0.15)
				(type solid)
			)
			(layer "F.SilkS")
		)
		(fp_line
			(start 2.101 1.601)
			(end -2.1 1.601)
			(stroke
				(width 0.15)
				(type solid)
			)
			(layer "F.SilkS")
		)
		(fp_line
			(start 2.101 1.601)
			(end 2.101 1.48)
			(stroke
				(width 0.15)
				(type solid)
			)
			(layer "F.SilkS")
		)
		(fp_rect
			(start 2.751 1.75)
			(end -2.748 -1.749)
			(stroke
				(width 0.05)
				(type solid)
			)
			(fill no)
			(layer "F.CrtYd")
		)
		(fp_line
			(start -2.1 -1.6)
			(end -2.1 1.601)
			(stroke
				(width 0.15)
				(type solid)
			)
			(layer "F.Fab")
		)
		(fp_line
			(start -2.1 1.601)
			(end 2.101 1.601)
			(stroke
				(width 0.15)
				(type solid)
			)
			(layer "F.Fab")
		)
		(fp_line
			(start -0.248 -0.8)
			(end 0.25 -0.8)
			(stroke
				(width 0.15)
				(type solid)
			)
			(layer "F.Fab")
		)
		(fp_line
			(start 0.25 0.802)
			(end -0.248 0.802)
			(stroke
				(width 0.15)
				(type solid)
			)
			(layer "F.Fab")
		)
		(fp_line
			(start 2.101 -1.6)
			(end -2.1 -1.6)
			(stroke
				(width 0.15)
				(type solid)
			)
			(layer "F.Fab")
		)
		(fp_line
			(start 2.101 1.601)
			(end 2.101 -1.6)
			(stroke
				(width 0.15)
				(type solid)
			)
			(layer "F.Fab")
		)
		(fp_arc
			(start -0.248 0.802)
			(mid -1.050001 0.001)
			(end -0.248 -0.8)
			(stroke
				(width 0.15)
				(type solid)
			)
			(layer "F.Fab")
		)
		(fp_arc
			(start 0.25 -0.8)
			(mid 1.051001 0.001)
			(end 0.25 0.802)
			(stroke
				(width 0.15)
				(type solid)
			)
			(layer "F.Fab")
		)
		(pad "1" smd rect
			(at -2.048 -0.8 180)
			(size 0.9 1)
			(layers "F.Cu" "F.Mask" "F.Paste")
			(net 1 "GND")
			(pinfunction "1")
			(pintype "passive")
		)
		(pad "2" smd rect
			(at 2.05 -0.8 180)
			(size 0.9 1)
			(layers "F.Cu" "F.Mask" "F.Paste")
			(net 1 "GND")
			(pinfunction "2")
			(pintype "passive")
		)
		(pad "3" smd rect
			(at -2.048 0.802 180)
			(size 0.9 1)
			(layers "F.Cu" "F.Mask" "F.Paste")
			(net 106 "HOT_SWAP_BUTTON")
			(pinfunction "3")
			(pintype "passive")
		)
		(pad "4" smd rect
			(at 2.05 0.802 180)
			(size 0.9 1)
			(layers "F.Cu" "F.Mask" "F.Paste")
			(net 106 "HOT_SWAP_BUTTON")
			(pinfunction "4")
			(pintype "passive")
		)
	)
	(footprint "antmicro-footprints:SC70-3"
		(layer "F.Cu")
		(at 83.650501 122.926 90)
		(property "Reference" "Q4"
			(at 0 -1.6 90)
			(layer "F.SilkS")
			(hide yes)
			(effects
				(font
					(size 0.7 0.7)
					(thickness 0.15)
				)
				(justify left bottom)
			)
		)
		(property "Value" "BSS138PW,115"
			(at 0 2.3 90)
			(layer "F.Fab")
			(effects
				(font
					(size 0.7 0.7)
					(thickness 0.15)
				)
				(justify left bottom)
			)
		)
		(property "Datasheet" "https://assets.nexperia.com/documents/data-sheet/BSS138PW.pdf"
			(at 0 0 90)
			(layer "F.Fab")
			(hide yes)
			(effects
				(font
					(size 1.27 1.27)
					(thickness 0.15)
				)
			)
		)
		(property "Description" "Power MOSFET, N Channel, 60 V, 320 mA, 0.9 ohm, SOT-323, Surface Mount"
			(at 0 0 90)
			(layer "F.Fab")
			(hide yes)
			(effects
				(font
					(size 1.27 1.27)
					(thickness 0.15)
				)
			)
		)
		(property "Author" "Antmicro"
			(at 206.576501 39.275499 0)
			(layer "F.Fab")
			(hide yes)
			(effects
				(font
					(size 1 1)
					(thickness 0.15)
				)
			)
		)
		(property "License" "Apache-2.0"
			(at 206.576501 39.275499 0)
			(layer "F.Fab")
			(hide yes)
			(effects
				(font
					(size 1 1)
					(thickness 0.15)
				)
			)
		)
		(property "MPN" "BSS138PW,115"
			(at 206.576501 39.275499 0)
			(layer "F.Fab")
			(hide yes)
			(effects
				(font
					(size 1 1)
					(thickness 0.15)
				)
			)
		)
		(property "Manufacturer" "Nexperia"
			(at 206.576501 39.275499 0)
			(layer "F.Fab")
			(hide yes)
			(effects
				(font
					(size 1 1)
					(thickness 0.15)
				)
			)
		)
		(sheetname "/FPGA bank 14/")
		(sheetfile "fpga-bank-14.kicad_sch")
		(attr smd)
		(fp_line
			(start -0.3 -1)
			(end 0.627 -0.999)
			(stroke
				(width 0.15)
				(type solid)
			)
			(layer "F.SilkS")
		)
		(fp_line
			(start 0.627 -0.6)
			(end 0.627 -0.999)
			(stroke
				(width 0.15)
				(type solid)
			)
			(layer "F.SilkS")
		)
		(fp_line
			(start 0.627 0.6)
			(end 0.627 1.001)
			(stroke
				(width 0.15)
				(type solid)
			)
			(layer "F.SilkS")
		)
		(fp_line
			(start -0.3 1)
			(end 0.627 1.001)
			(stroke
				(width 0.15)
				(type solid)
			)
			(layer "F.SilkS")
		)
		(fp_line
			(start 0.9 -1.3)
			(end 0.9 -0.4)
			(stroke
				(width 0.05)
				(type solid)
			)
			(layer "F.CrtYd")
		)
		(fp_line
			(start -0.9 -1.3)
			(end 0.9 -1.3)
			(stroke
				(width 0.05)
				(type solid)
			)
			(layer "F.CrtYd")
		)
		(fp_line
			(start -0.9 -1.3)
			(end -0.9 -1)
			(stroke
				(width 0.05)
				(type solid)
			)
			(layer "F.CrtYd")
		)
		(fp_line
			(start -0.9 -1)
			(end -1.4 -1)
			(stroke
				(width 0.05)
				(type solid)
			)
			(layer "F.CrtYd")
		)
		(fp_line
			(start 1.4 -0.4)
			(end 1.4 0.4)
			(stroke
				(width 0.05)
				(type solid)
			)
			(layer "F.CrtYd")
		)
		(fp_line
			(start 0.9 -0.4)
			(end 1.4 -0.4)
			(stroke
				(width 0.05)
				(type solid)
			)
			(layer "F.CrtYd")
		)
		(fp_line
			(start 1.4 0.4)
			(end 0.9 0.4)
			(stroke
				(width 0.05)
				(type solid)
			)
			(layer "F.CrtYd")
		)
		(fp_line
			(start 0.9 0.4)
			(end 0.9 1.3)
			(stroke
				(width 0.05)
				(type solid)
			)
			(layer "F.CrtYd")
		)
		(fp_line
			(start -0.9 1)
			(end -1.4 1)
			(stroke
				(width 0.05)
				(type solid)
			)
			(layer "F.CrtYd")
		)
		(fp_line
			(start -1.4 1)
			(end -1.4 -1)
			(stroke
				(width 0.05)
				(type solid)
			)
			(layer "F.CrtYd")
		)
		(fp_line
			(start 0.9 1.3)
			(end -0.9 1.3)
			(stroke
				(width 0.05)
				(type solid)
			)
			(layer "F.CrtYd")
		)
		(fp_line
			(start -0.9 1.3)
			(end -0.9 1)
			(stroke
				(width 0.05)
				(type solid)
			)
			(layer "F.CrtYd")
		)
		(fp_rect
			(start -0.623 -0.999)
			(end 0.627 1.001)
			(stroke
				(width 0.15)
				(type solid)
			)
			(fill no)
			(layer "F.Fab")
		)
		(pad "1" smd rect
			(at -1.051 -0.65 180)
			(size 0.6 0.6)
			(layers "F.Cu" "F.Mask" "F.Paste")
			(net 615 "/FPGA bank 14/USR_LED1")
			(pinfunction "G")
			(pintype "input")
		)
		(pad "2" smd rect
			(at -1.051 0.65 180)
			(size 0.6 0.6)
			(layers "F.Cu" "F.Mask" "F.Paste")
			(net 1 "GND")
			(pinfunction "S")
			(pintype "passive")
		)
		(pad "3" smd rect
			(at 1.05 0 180)
			(size 0.6 0.6)
			(layers "F.Cu" "F.Mask" "F.Paste")
			(net 353 "Net-(Q4-D)")
			(pinfunction "D")
			(pintype "passive")
		)
	)
	(footprint "antmicro-footprints:R_0402_1005Metric"
		(layer "F.Cu")
		(at 77.7 153.2 180)
		(descr "Resistor SMD 0402")
		(tags "resistor SMD 0402")
		(property "Reference" "R68"
			(at -1.122484 -0.772697 180)
			(layer "F.SilkS")
			(hide yes)
			(effects
				(font
					(size 0.7 0.7)
					(thickness 0.15)
				)
				(justify left bottom)
			)
		)
		(property "Value" "R_5k11_0402"
			(at -1.011843 1.772047 180)
			(layer "F.Fab")
			(effects
				(font
					(size 0.7 0.7)
					(thickness 0.15)
				)
				(justify left bottom)
			)
		)
		(property "Datasheet" "https://www.bourns.com/docs/product-datasheets/cr.pdf"
			(at 0 0 180)
			(layer "F.Fab")
			(hide yes)
			(effects
				(font
					(size 1.27 1.27)
					(thickness 0.15)
				)
			)
		)
		(property "Author" "Antmicro"
			(at 155.4 306.4 0)
			(layer "F.Fab")
			(hide yes)
			(effects
				(font
					(size 1 1)
					(thickness 0.15)
				)
			)
		)
		(property "License" "Apache-2.0"
			(at 155.4 306.4 0)
			(layer "F.Fab")
			(hide yes)
			(effects
				(font
					(size 1 1)
					(thickness 0.15)
				)
			)
		)
		(property "MPN" "CR0402-FX-5111GLF"
			(at 155.4 306.4 0)
			(layer "F.Fab")
			(hide yes)
			(effects
				(font
					(size 1 1)
					(thickness 0.15)
				)
			)
		)
		(property "Manufacturer" "Bourns"
			(at 155.4 306.4 0)
			(layer "F.Fab")
			(hide yes)
			(effects
				(font
					(size 1 1)
					(thickness 0.15)
				)
			)
		)
		(property "Tolerance" "1%"
			(at 155.4 306.4 0)
			(layer "F.Fab")
			(hide yes)
			(effects
				(font
					(size 1 1)
					(thickness 0.15)
				)
			)
		)
		(property "Val" "5k11"
			(at 155.4 306.4 0)
			(layer "F.Fab")
			(hide yes)
			(effects
				(font
					(size 1 1)
					(thickness 0.15)
				)
			)
		)
		(sheetname "/Debug FTDI/")
		(sheetfile "debug-ftdi.kicad_sch")
		(attr smd)
		(fp_rect
			(start -0.93 -0.47)
			(end 0.93 0.47)
			(stroke
				(width 0.05)
				(type solid)
			)
			(fill no)
			(layer "F.CrtYd")
		)
		(fp_rect
			(start -0.5 -0.25)
			(end 0.5 0.25)
			(stroke
				(width 0.15)
				(type solid)
			)
			(fill no)
			(layer "F.Fab")
		)
		(pad "1" smd roundrect
			(at -0.485 0 180)
			(size 0.59 0.64)
			(layers "F.Cu" "F.Mask" "F.Paste")
			(roundrect_rratio 0.25)
			(net 1 "GND")
			(pintype "passive")
		)
		(pad "2" smd roundrect
			(at 0.485 0 180)
			(size 0.59 0.64)
			(layers "F.Cu" "F.Mask" "F.Paste")
			(roundrect_rratio 0.25)
			(net 321 "Net-(J3-CC_{1})")
			(pintype "passive")
		)
	)
	(footprint "antmicro-footprints:SC70-3"
		(layer "F.Cu")
		(at 91.750501 129.249 90)
		(property "Reference" "Q3"
			(at 0 -1.6 90)
			(layer "F.SilkS")
			(hide yes)
			(effects
				(font
					(size 0.7 0.7)
					(thickness 0.15)
				)
				(justify left bottom)
			)
		)
		(property "Value" "BSS138PW,115"
			(at 0 2.3 90)
			(layer "F.Fab")
			(effects
				(font
					(size 0.7 0.7)
					(thickness 0.15)
				)
				(justify left bottom)
			)
		)
		(property "Datasheet" "https://assets.nexperia.com/documents/data-sheet/BSS138PW.pdf"
			(at 0 0 90)
			(layer "F.Fab")
			(hide yes)
			(effects
				(font
					(size 1.27 1.27)
					(thickness 0.15)
				)
			)
		)
		(property "Description" "Power MOSFET, N Channel, 60 V, 320 mA, 0.9 ohm, SOT-323, Surface Mount"
			(at 0 0 90)
			(layer "F.Fab")
			(hide yes)
			(effects
				(font
					(size 1.27 1.27)
					(thickness 0.15)
				)
			)
		)
		(property "Author" "Antmicro"
			(at 220.999501 37.498499 0)
			(layer "F.Fab")
			(hide yes)
			(effects
				(font
					(size 1 1)
					(thickness 0.15)
				)
			)
		)
		(property "License" "Apache-2.0"
			(at 220.999501 37.498499 0)
			(layer "F.Fab")
			(hide yes)
			(effects
				(font
					(size 1 1)
					(thickness 0.15)
				)
			)
		)
		(property "MPN" "BSS138PW,115"
			(at 220.999501 37.498499 0)
			(layer "F.Fab")
			(hide yes)
			(effects
				(font
					(size 1 1)
					(thickness 0.15)
				)
			)
		)
		(property "Manufacturer" "Nexperia"
			(at 220.999501 37.498499 0)
			(layer "F.Fab")
			(hide yes)
			(effects
				(font
					(size 1 1)
					(thickness 0.15)
				)
			)
		)
		(sheetname "/FPGA Config/")
		(sheetfile "fpga-config.kicad_sch")
		(attr smd)
		(fp_line
			(start -0.3 -1)
			(end 0.627 -0.999)
			(stroke
				(width 0.15)
				(type solid)
			)
			(layer "F.SilkS")
		)
		(fp_line
			(start 0.627 -0.6)
			(end 0.627 -0.999)
			(stroke
				(width 0.15)
				(type solid)
			)
			(layer "F.SilkS")
		)
		(fp_line
			(start 0.627 0.6)
			(end 0.627 1.001)
			(stroke
				(width 0.15)
				(type solid)
			)
			(layer "F.SilkS")
		)
		(fp_line
			(start -0.3 1)
			(end 0.627 1.001)
			(stroke
				(width 0.15)
				(type solid)
			)
			(layer "F.SilkS")
		)
		(fp_line
			(start 0.9 -1.3)
			(end 0.9 -0.4)
			(stroke
				(width 0.05)
				(type solid)
			)
			(layer "F.CrtYd")
		)
		(fp_line
			(start -0.9 -1.3)
			(end 0.9 -1.3)
			(stroke
				(width 0.05)
				(type solid)
			)
			(layer "F.CrtYd")
		)
		(fp_line
			(start -0.9 -1.3)
			(end -0.9 -1)
			(stroke
				(width 0.05)
				(type solid)
			)
			(layer "F.CrtYd")
		)
		(fp_line
			(start -0.9 -1)
			(end -1.4 -1)
			(stroke
				(width 0.05)
				(type solid)
			)
			(layer "F.CrtYd")
		)
		(fp_line
			(start 1.4 -0.4)
			(end 1.4 0.4)
			(stroke
				(width 0.05)
				(type solid)
			)
			(layer "F.CrtYd")
		)
		(fp_line
			(start 0.9 -0.4)
			(end 1.4 -0.4)
			(stroke
				(width 0.05)
				(type solid)
			)
			(layer "F.CrtYd")
		)
		(fp_line
			(start 1.4 0.4)
			(end 0.9 0.4)
			(stroke
				(width 0.05)
				(type solid)
			)
			(layer "F.CrtYd")
		)
		(fp_line
			(start 0.9 0.4)
			(end 0.9 1.3)
			(stroke
				(width 0.05)
				(type solid)
			)
			(layer "F.CrtYd")
		)
		(fp_line
			(start -0.9 1)
			(end -1.4 1)
			(stroke
				(width 0.05)
				(type solid)
			)
			(layer "F.CrtYd")
		)
		(fp_line
			(start -1.4 1)
			(end -1.4 -1)
			(stroke
				(width 0.05)
				(type solid)
			)
			(layer "F.CrtYd")
		)
		(fp_line
			(start 0.9 1.3)
			(end -0.9 1.3)
			(stroke
				(width 0.05)
				(type solid)
			)
			(layer "F.CrtYd")
		)
		(fp_line
			(start -0.9 1.3)
			(end -0.9 1)
			(stroke
				(width 0.05)
				(type solid)
			)
			(layer "F.CrtYd")
		)
		(fp_rect
			(start -0.623 -0.999)
			(end 0.627 1.001)
			(stroke
				(width 0.15)
				(type solid)
			)
			(fill no)
			(layer "F.Fab")
		)
		(pad "1" smd rect
			(at -1.051 -0.65 180)
			(size 0.6 0.6)
			(layers "F.Cu" "F.Mask" "F.Paste")
			(net 614 "/FPGA Config/INIT_B")
			(pinfunction "G")
			(pintype "input")
		)
		(pad "2" smd rect
			(at -1.051 0.65 180)
			(size 0.6 0.6)
			(layers "F.Cu" "F.Mask" "F.Paste")
			(net 1 "GND")
			(pinfunction "S")
			(pintype "passive")
		)
		(pad "3" smd rect
			(at 1.05 0 180)
			(size 0.6 0.6)
			(layers "F.Cu" "F.Mask" "F.Paste")
			(net 352 "Net-(Q3-D)")
			(pinfunction "D")
			(pintype "passive")
		)
	)
)
